(kicad_pcb
	(version 20260206)
	(generator "pcbnew")
	(generator_version "10.0")
	(general
		(thickness 1.6)
		(legacy_teardrops no)
	)
	(paper "A4")
	(title_block
		(title "01162023_DA0F0TEBIF0_F0T_Expander_BD_F_brd_V02_OCP.brd")
		(comment 1 "Grand Teton / footprints 3263-3268 of 9728")
	)
	(layers
		(0 "F.Cu" signal "TOP")
		(4 "In1.Cu" signal "GND")
		(6 "In2.Cu" signal "VCC")
		(8 "In3.Cu" signal "VCC1")
		(10 "In4.Cu" signal "GND1")
		(12 "In5.Cu" signal "IN1")
		(14 "In6.Cu" signal "GND2")
		(16 "In7.Cu" signal "IN2")
		(18 "In8.Cu" signal "GND3")
		(20 "In9.Cu" signal "IN3")
		(22 "In10.Cu" signal "GND4")
		(24 "In11.Cu" signal "IN4")
		(26 "In12.Cu" signal "GND5")
		(28 "In13.Cu" signal "IN5")
		(30 "In14.Cu" signal "GND6")
		(32 "In15.Cu" signal "IN6")
		(34 "In16.Cu" signal "GND7")
		(2 "B.Cu" signal "BOTTOM")
		(9 "F.Adhes" user "F.Adhesive")
		(11 "B.Adhes" user "B.Adhesive")
		(13 "F.Paste" user "Package Geometry/Pastemask Top")
		(15 "B.Paste" user "Package Geometry/Pastemask Bottom")
		(5 "F.SilkS" user "Ref Des/Silkscreen Top")
		(7 "B.SilkS" user "Ref Des/Silkscreen Bottom")
		(1 "F.Mask" user "Board Geometry/Soldermask Top")
		(3 "B.Mask" user "Board Geometry/Soldermask Bottom")
		(17 "Dwgs.User" user "User.Drawings")
		(19 "Cmts.User" user "User.Comments")
		(21 "Eco1.User" user "User.Eco1")
		(23 "Eco2.User" user "User.Eco2")
		(25 "Edge.Cuts" user "Board Geometry/Outline")
		(27 "Margin" user)
		(31 "F.CrtYd" user "Package Geometry/Place Bound Top")
		(29 "B.CrtYd" user "Package Geometry/Place Bound Bottom")
		(35 "F.Fab" user "Ref Des/Assembly Top")
		(33 "B.Fab" user "Ref Des/Assembly Bottom")
	)
	(footprint ""
		(layer "F.Cu")
		(at 458.935836 -111.896906 90)
		(property "Reference" "PR7060"
			(at 0 0 90)
			(layer "F.SilkS")
			(hide yes)
			(effects
				(font
					(size 1.27 1.27)
				)
			)
		)
		(property "Value" ""
			(at 0 0 90)
			(layer "F.Fab")
			(effects
				(font
					(size 1.27 1.27)
				)
			)
		)
		(duplicate_pad_numbers_are_jumpers no)
		(fp_line
			(start 0.7874 -0.4064)
			(end 0.7874 0.4064)
			(stroke
				(width 0.1524)
				(type default)
			)
			(layer "F.SilkS")
		)
		(fp_line
			(start -0.7874 -0.4064)
			(end 0.7874 -0.4064)
			(stroke
				(width 0.1524)
				(type default)
			)
			(layer "F.SilkS")
		)
		(fp_line
			(start 0.7874 0.4064)
			(end -0.7874 0.4064)
			(stroke
				(width 0.1524)
				(type default)
			)
			(layer "F.SilkS")
		)
		(fp_line
			(start -0.7874 0.4064)
			(end -0.7874 -0.4064)
			(stroke
				(width 0.1524)
				(type default)
			)
			(layer "F.SilkS")
		)
		(fp_line
			(start -0.12065 -0.305054)
			(end -0.12065 -0.2794)
			(stroke
				(width 0.1)
				(type default)
			)
			(layer "F.Fab")
		)
		(fp_line
			(start -0.67945 -0.305054)
			(end -0.12065 -0.305054)
			(stroke
				(width 0.1)
				(type default)
			)
			(layer "F.Fab")
		)
		(fp_line
			(start 0.67945 -0.3048)
			(end 0.67945 0.3048)
			(stroke
				(width 0.1)
				(type default)
			)
			(layer "F.Fab")
		)
		(fp_line
			(start 0.12065 -0.3048)
			(end 0.67945 -0.3048)
			(stroke
				(width 0.1)
				(type default)
			)
			(layer "F.Fab")
		)
		(fp_line
			(start 0.12065 -0.2794)
			(end 0.12065 -0.3048)
			(stroke
				(width 0.1)
				(type default)
			)
			(layer "F.Fab")
		)
		(fp_line
			(start -0.12065 -0.2794)
			(end 0.12065 -0.2794)
			(stroke
				(width 0.1)
				(type default)
			)
			(layer "F.Fab")
		)
		(fp_line
			(start 0.120396 0.2794)
			(end -0.12065 0.2794)
			(stroke
				(width 0.1)
				(type default)
			)
			(layer "F.Fab")
		)
		(fp_line
			(start -0.12065 0.2794)
			(end -0.12065 0.3048)
			(stroke
				(width 0.1)
				(type default)
			)
			(layer "F.Fab")
		)
		(fp_line
			(start 0.67945 0.3048)
			(end 0.120396 0.3048)
			(stroke
				(width 0.1)
				(type default)
			)
			(layer "F.Fab")
		)
		(fp_line
			(start 0.120396 0.3048)
			(end 0.120396 0.2794)
			(stroke
				(width 0.1)
				(type default)
			)
			(layer "F.Fab")
		)
		(fp_line
			(start -0.12065 0.3048)
			(end -0.67945 0.3048)
			(stroke
				(width 0.1)
				(type default)
			)
			(layer "F.Fab")
		)
		(fp_line
			(start -0.67945 0.3048)
			(end -0.67945 -0.305054)
			(stroke
				(width 0.1)
				(type default)
			)
			(layer "F.Fab")
		)
		(pad "1" smd circle
			(at -0.40005 0 90)
			(size 0 0)
			(layers "F.Cu" "F.Mask" "F.Paste")
			(net "P12V_NIC7_CO_ISET")
		)
		(pad "2" smd circle
			(at 0.40005 0 90)
			(size 0 0)
			(layers "F.Cu" "F.Mask" "F.Paste")
			(net "P12V_NIC7_CO_ISET_R")
		)
	)
	(footprint ""
		(layer "F.Cu")
		(at 61.173868 -388.33679 -90)
		(property "Reference" "C4041"
			(at 0 0 270)
			(layer "F.SilkS")
			(hide yes)
			(effects
				(font
					(size 1.27 1.27)
				)
			)
		)
		(property "Value" ""
			(at 0 0 270)
			(layer "F.Fab")
			(effects
				(font
					(size 1.27 1.27)
				)
			)
		)
		(duplicate_pad_numbers_are_jumpers no)
		(fp_line
			(start -0.7874 0.4064)
			(end -0.7874 -0.4064)
			(stroke
				(width 0.1524)
				(type default)
			)
			(layer "F.SilkS")
		)
		(fp_line
			(start 0.7874 0.4064)
			(end -0.7874 0.4064)
			(stroke
				(width 0.1524)
				(type default)
			)
			(layer "F.SilkS")
		)
		(fp_line
			(start -0.7874 -0.4064)
			(end 0.7874 -0.4064)
			(stroke
				(width 0.1524)
				(type default)
			)
			(layer "F.SilkS")
		)
		(fp_line
			(start 0.7874 -0.4064)
			(end 0.7874 0.4064)
			(stroke
				(width 0.1524)
				(type default)
			)
			(layer "F.SilkS")
		)
		(fp_line
			(start -0.67945 0.3048)
			(end -0.67945 -0.305054)
			(stroke
				(width 0.1)
				(type default)
			)
			(layer "F.Fab")
		)
		(fp_line
			(start -0.12065 0.3048)
			(end -0.67945 0.3048)
			(stroke
				(width 0.1)
				(type default)
			)
			(layer "F.Fab")
		)
		(fp_line
			(start 0.120396 0.3048)
			(end 0.120396 0.2794)
			(stroke
				(width 0.1)
				(type default)
			)
			(layer "F.Fab")
		)
		(fp_line
			(start 0.67945 0.3048)
			(end 0.120396 0.3048)
			(stroke
				(width 0.1)
				(type default)
			)
			(layer "F.Fab")
		)
		(fp_line
			(start -0.12065 0.2794)
			(end -0.12065 0.3048)
			(stroke
				(width 0.1)
				(type default)
			)
			(layer "F.Fab")
		)
		(fp_line
			(start 0.120396 0.2794)
			(end -0.12065 0.2794)
			(stroke
				(width 0.1)
				(type default)
			)
			(layer "F.Fab")
		)
		(fp_line
			(start -0.12065 -0.2794)
			(end 0.12065 -0.2794)
			(stroke
				(width 0.1)
				(type default)
			)
			(layer "F.Fab")
		)
		(fp_line
			(start 0.12065 -0.2794)
			(end 0.12065 -0.3048)
			(stroke
				(width 0.1)
				(type default)
			)
			(layer "F.Fab")
		)
		(fp_line
			(start 0.12065 -0.3048)
			(end 0.67945 -0.3048)
			(stroke
				(width 0.1)
				(type default)
			)
			(layer "F.Fab")
		)
		(fp_line
			(start 0.67945 -0.3048)
			(end 0.67945 0.3048)
			(stroke
				(width 0.1)
				(type default)
			)
			(layer "F.Fab")
		)
		(fp_line
			(start -0.67945 -0.305054)
			(end -0.12065 -0.305054)
			(stroke
				(width 0.1)
				(type default)
			)
			(layer "F.Fab")
		)
		(fp_line
			(start -0.12065 -0.305054)
			(end -0.12065 -0.2794)
			(stroke
				(width 0.1)
				(type default)
			)
			(layer "F.Fab")
		)
		(pad "1" smd circle
			(at -0.40005 0 270)
			(size 0 0)
			(layers "F.Cu" "F.Mask" "F.Paste")
			(net "GND")
		)
		(pad "2" smd circle
			(at 0.40005 0 270)
			(size 0 0)
			(layers "F.Cu" "F.Mask" "F.Paste")
			(net "GPU_PWR_BRAKE_N")
		)
	)
	(footprint ""
		(layer "F.Cu")
		(at 226.377754 -239.93729)
		(property "Reference" "U418"
			(at -2.032 -2.377948 0)
			(unlocked yes)
			(layer "F.SilkS")
			(effects
				(font
					(size 0.7874 0.5842)
					(thickness 0.1524)
				)
				(justify left)
			)
		)
		(property "Value" ""
			(at 0 0 0)
			(layer "F.Fab")
			(effects
				(font
					(size 1.27 1.27)
				)
			)
		)
		(duplicate_pad_numbers_are_jumpers no)
		(fp_line
			(start -2.0574 -1.651)
			(end -0.381 -1.651)
			(stroke
				(width 0.1524)
				(type default)
			)
			(layer "F.SilkS")
		)
		(fp_line
			(start -2.0574 1.651)
			(end -2.0574 -1.651)
			(stroke
				(width 0.1524)
				(type default)
			)
			(layer "F.SilkS")
		)
		(fp_line
			(start -0.381 -1.651)
			(end 0 -1.016)
			(stroke
				(width 0.1524)
				(type default)
			)
			(layer "F.SilkS")
		)
		(fp_line
			(start 0 -1.016)
			(end 0.381 -1.651)
			(stroke
				(width 0.1524)
				(type default)
			)
			(layer "F.SilkS")
		)
		(fp_line
			(start 0.381 -1.651)
			(end 2.0574 -1.651)
			(stroke
				(width 0.1524)
				(type default)
			)
			(layer "F.SilkS")
		)
		(fp_line
			(start 2.0574 -1.651)
			(end 2.0574 1.651)
			(stroke
				(width 0.1524)
				(type default)
			)
			(layer "F.SilkS")
		)
		(fp_line
			(start 2.0574 1.651)
			(end -2.0574 1.651)
			(stroke
				(width 0.1524)
				(type default)
			)
			(layer "F.SilkS")
		)
		(fp_poly
			(pts
				(xy -2.71272 -0.719328) (xy -2.71272 -1.344168) (xy -2.159 -1.016)
			)
			(stroke
				(width 0)
				(type default)
			)
			(fill yes)
			(layer "F.SilkS")
		)
		(fp_line
			(start -1.599946 -1.199896)
			(end -0.899922 -1.199896)
			(stroke
				(width 0.1)
				(type default)
			)
			(layer "F.Fab")
		)
		(fp_line
			(start -1.599946 1.199896)
			(end -1.599946 -1.199896)
			(stroke
				(width 0.1)
				(type default)
			)
			(layer "F.Fab")
		)
		(fp_line
			(start -0.899922 -1.549908)
			(end 0.899922 -1.549908)
			(stroke
				(width 0.1)
				(type default)
			)
			(layer "F.Fab")
		)
		(fp_line
			(start -0.899922 -1.199896)
			(end -0.899922 -1.549908)
			(stroke
				(width 0.1)
				(type default)
			)
			(layer "F.Fab")
		)
		(fp_line
			(start -0.899922 1.199896)
			(end -1.599946 1.199896)
			(stroke
				(width 0.1)
				(type default)
			)
			(layer "F.Fab")
		)
		(fp_line
			(start -0.899922 1.549908)
			(end -0.899922 1.199896)
			(stroke
				(width 0.1)
				(type default)
			)
			(layer "F.Fab")
		)
		(fp_line
			(start 0.899922 -1.549908)
			(end 0.899922 -1.199896)
			(stroke
				(width 0.1)
				(type default)
			)
			(layer "F.Fab")
		)
		(fp_line
			(start 0.899922 -1.199896)
			(end 1.599946 -1.199896)
			(stroke
				(width 0.1)
				(type default)
			)
			(layer "F.Fab")
		)
		(fp_line
			(start 0.899922 1.199896)
			(end 0.899922 1.549908)
			(stroke
				(width 0.1)
				(type default)
			)
			(layer "F.Fab")
		)
		(fp_line
			(start 0.899922 1.549908)
			(end -0.899922 1.549908)
			(stroke
				(width 0.1)
				(type default)
			)
			(layer "F.Fab")
		)
		(fp_line
			(start 1.599946 -1.199896)
			(end 1.599946 1.199896)
			(stroke
				(width 0.1)
				(type default)
			)
			(layer "F.Fab")
		)
		(fp_line
			(start 1.599946 1.199896)
			(end 0.899922 1.199896)
			(stroke
				(width 0.1)
				(type default)
			)
			(layer "F.Fab")
		)
		(fp_poly
			(pts
				(xy -2.71272 -0.719328) (xy -2.71272 -1.344168) (xy -2.159 -1.016)
			)
			(stroke
				(width 0)
				(type default)
			)
			(fill yes)
			(layer "F.Fab")
		)
		(pad "1" smd rect
			(at -1.225042 -0.94996 270)
			(size 0.5588 1.3462)
			(layers "F.Cu" "F.Mask" "F.Paste")
			(net "BIC_UART_BMC_SEL_R")
		)
		(pad "2" smd rect
			(at -1.225042 0 270)
			(size 0.5588 1.3462)
			(layers "F.Cu" "F.Mask" "F.Paste")
			(net "BIC_UART_BIC_SEL_R")
		)
		(pad "3" smd rect
			(at -1.225042 0.94996 270)
			(size 0.5588 1.3462)
			(layers "F.Cu" "F.Mask" "F.Paste")
			(net "GND")
		)
		(pad "4" smd rect
			(at 1.225042 0.94996 270)
			(size 0.5588 1.3462)
			(layers "F.Cu" "F.Mask" "F.Paste")
			(net "BIC_UART_SW_SEL1")
		)
		(pad "5" smd rect
			(at 1.225042 -0.94996 270)
			(size 0.5588 1.3462)
			(layers "F.Cu" "F.Mask" "F.Paste")
			(net "P3V3_AUX")
		)
	)
	(footprint ""
		(layer "F.Cu")
		(at 430.961546 -148.91131 180)
		(property "Reference" "C642"
			(at 0 0 180)
			(layer "F.SilkS")
			(hide yes)
			(effects
				(font
					(size 1.27 1.27)
				)
			)
		)
		(property "Value" ""
			(at 0 0 180)
			(layer "F.Fab")
			(effects
				(font
					(size 1.27 1.27)
				)
			)
		)
		(duplicate_pad_numbers_are_jumpers no)
		(fp_line
			(start 0.299974 0.150114)
			(end -0.299974 0.150114)
			(stroke
				(width 0.1)
				(type default)
			)
			(layer "F.Fab")
		)
		(fp_line
			(start 0.299974 -0.150114)
			(end 0.299974 0.150114)
			(stroke
				(width 0.1)
				(type default)
			)
			(layer "F.Fab")
		)
		(fp_line
			(start -0.299974 0.150114)
			(end -0.299974 -0.150114)
			(stroke
				(width 0.1)
				(type default)
			)
			(layer "F.Fab")
		)
		(fp_line
			(start -0.299974 -0.150114)
			(end 0.299974 -0.150114)
			(stroke
				(width 0.1)
				(type default)
			)
			(layer "F.Fab")
		)
		(pad "1" smd rect
			(at -0.2667 0 180)
			(size 0.3048 0.381)
			(layers "F.Cu" "F.Mask" "F.Paste")
			(net "P5E_PEX3_STN0_TX_DP<11>")
		)
		(pad "2" smd rect
			(at 0.2667 0 180)
			(size 0.3048 0.381)
			(layers "F.Cu" "F.Mask" "F.Paste")
			(net "P5E_PEX3_STN0_TX_C_DP<11>")
		)
	)
	(footprint ""
		(layer "F.Cu")
		(at 320.451988 -228.604318 -90)
		(property "Reference" "R2988"
			(at 0 0 270)
			(layer "F.SilkS")
			(hide yes)
			(effects
				(font
					(size 1.27 1.27)
				)
			)
		)
		(property "Value" ""
			(at 0 0 270)
			(layer "F.Fab")
			(effects
				(font
					(size 1.27 1.27)
				)
			)
		)
		(duplicate_pad_numbers_are_jumpers no)
		(fp_line
			(start -0.7874 0.4064)
			(end -0.7874 -0.4064)
			(stroke
				(width 0.1524)
				(type default)
			)
			(layer "F.SilkS")
		)
		(fp_line
			(start 0.7874 0.4064)
			(end -0.7874 0.4064)
			(stroke
				(width 0.1524)
				(type default)
			)
			(layer "F.SilkS")
		)
		(fp_line
			(start -0.7874 -0.4064)
			(end 0.7874 -0.4064)
			(stroke
				(width 0.1524)
				(type default)
			)
			(layer "F.SilkS")
		)
		(fp_line
			(start 0.7874 -0.4064)
			(end 0.7874 0.4064)
			(stroke
				(width 0.1524)
				(type default)
			)
			(layer "F.SilkS")
		)
		(fp_line
			(start -0.67945 0.3048)
			(end -0.67945 -0.305054)
			(stroke
				(width 0.1)
				(type default)
			)
			(layer "F.Fab")
		)
		(fp_line
			(start -0.12065 0.3048)
			(end -0.67945 0.3048)
			(stroke
				(width 0.1)
				(type default)
			)
			(layer "F.Fab")
		)
		(fp_line
			(start 0.120396 0.3048)
			(end 0.120396 0.2794)
			(stroke
				(width 0.1)
				(type default)
			)
			(layer "F.Fab")
		)
		(fp_line
			(start 0.67945 0.3048)
			(end 0.120396 0.3048)
			(stroke
				(width 0.1)
				(type default)
			)
			(layer "F.Fab")
		)
		(fp_line
			(start -0.12065 0.2794)
			(end -0.12065 0.3048)
			(stroke
				(width 0.1)
				(type default)
			)
			(layer "F.Fab")
		)
		(fp_line
			(start 0.120396 0.2794)
			(end -0.12065 0.2794)
			(stroke
				(width 0.1)
				(type default)
			)
			(layer "F.Fab")
		)
		(fp_line
			(start -0.12065 -0.2794)
			(end 0.12065 -0.2794)
			(stroke
				(width 0.1)
				(type default)
			)
			(layer "F.Fab")
		)
		(fp_line
			(start 0.12065 -0.2794)
			(end 0.12065 -0.3048)
			(stroke
				(width 0.1)
				(type default)
			)
			(layer "F.Fab")
		)
		(fp_line
			(start 0.12065 -0.3048)
			(end 0.67945 -0.3048)
			(stroke
				(width 0.1)
				(type default)
			)
			(layer "F.Fab")
		)
		(fp_line
			(start 0.67945 -0.3048)
			(end 0.67945 0.3048)
			(stroke
				(width 0.1)
				(type default)
			)
			(layer "F.Fab")
		)
		(fp_line
			(start -0.67945 -0.305054)
			(end -0.12065 -0.305054)
			(stroke
				(width 0.1)
				(type default)
			)
			(layer "F.Fab")
		)
		(fp_line
			(start -0.12065 -0.305054)
			(end -0.12065 -0.2794)
			(stroke
				(width 0.1)
				(type default)
			)
			(layer "F.Fab")
		)
		(pad "1" smd circle
			(at -0.40005 0 270)
			(size 0 0)
			(layers "F.Cu" "F.Mask" "F.Paste")
			(net "FPGA_DEBUG_LED_N")
		)
		(pad "2" smd circle
			(at 0.40005 0 270)
			(size 0 0)
			(layers "F.Cu" "F.Mask" "F.Paste")
			(net "FPGA_DEBUG_LED_R_N")
		)
	)
	(footprint ""
		(layer "F.Cu")
		(at 352.639884 -235.11383 -90)
		(property "Reference" "R5912"
			(at 0 0 270)
			(layer "F.SilkS")
			(hide yes)
			(effects
				(font
					(size 1.27 1.27)
				)
			)
		)
		(property "Value" ""
			(at 0 0 270)
			(layer "F.Fab")
			(effects
				(font
					(size 1.27 1.27)
				)
			)
		)
		(duplicate_pad_numbers_are_jumpers no)
		(fp_line
			(start -0.7874 0.4064)
			(end -0.7874 -0.4064)
			(stroke
				(width 0.1524)
				(type default)
			)
			(layer "F.SilkS")
		)
		(fp_line
			(start 0.7874 0.4064)
			(end -0.7874 0.4064)
			(stroke
				(width 0.1524)
				(type default)
			)
			(layer "F.SilkS")
		)
		(fp_line
			(start -0.7874 -0.4064)
			(end 0.7874 -0.4064)
			(stroke
				(width 0.1524)
				(type default)
			)
			(layer "F.SilkS")
		)
		(fp_line
			(start 0.7874 -0.4064)
			(end 0.7874 0.4064)
			(stroke
				(width 0.1524)
				(type default)
			)
			(layer "F.SilkS")
		)
		(fp_line
			(start -0.67945 0.3048)
			(end -0.67945 -0.305054)
			(stroke
				(width 0.1)
				(type default)
			)
			(layer "F.Fab")
		)
		(fp_line
			(start -0.12065 0.3048)
			(end -0.67945 0.3048)
			(stroke
				(width 0.1)
				(type default)
			)
			(layer "F.Fab")
		)
		(fp_line
			(start 0.120396 0.3048)
			(end 0.120396 0.2794)
			(stroke
				(width 0.1)
				(type default)
			)
			(layer "F.Fab")
		)
		(fp_line
			(start 0.67945 0.3048)
			(end 0.120396 0.3048)
			(stroke
				(width 0.1)
				(type default)
			)
			(layer "F.Fab")
		)
		(fp_line
			(start -0.12065 0.2794)
			(end -0.12065 0.3048)
			(stroke
				(width 0.1)
				(type default)
			)
			(layer "F.Fab")
		)
		(fp_line
			(start 0.120396 0.2794)
			(end -0.12065 0.2794)
			(stroke
				(width 0.1)
				(type default)
			)
			(layer "F.Fab")
		)
		(fp_line
			(start -0.12065 -0.2794)
			(end 0.12065 -0.2794)
			(stroke
				(width 0.1)
				(type default)
			)
			(layer "F.Fab")
		)
		(fp_line
			(start 0.12065 -0.2794)
			(end 0.12065 -0.3048)
			(stroke
				(width 0.1)
				(type default)
			)
			(layer "F.Fab")
		)
		(fp_line
			(start 0.12065 -0.3048)
			(end 0.67945 -0.3048)
			(stroke
				(width 0.1)
				(type default)
			)
			(layer "F.Fab")
		)
		(fp_line
			(start 0.67945 -0.3048)
			(end 0.67945 0.3048)
			(stroke
				(width 0.1)
				(type default)
			)
			(layer "F.Fab")
		)
		(fp_line
			(start -0.67945 -0.305054)
			(end -0.12065 -0.305054)
			(stroke
				(width 0.1)
				(type default)
			)
			(layer "F.Fab")
		)
		(fp_line
			(start -0.12065 -0.305054)
			(end -0.12065 -0.2794)
			(stroke
				(width 0.1)
				(type default)
			)
			(layer "F.Fab")
		)
		(pad "1" smd circle
			(at -0.40005 0 270)
			(size 0 0)
			(layers "F.Cu" "F.Mask" "F.Paste")
			(net "BIC_FORCE_THROTTLE_R_N")
		)
		(pad "2" smd circle
			(at 0.40005 0 270)
			(size 0 0)
			(layers "F.Cu" "F.Mask" "F.Paste")
			(net "P3V3_AUX")
		)
	)
)
